(kicad_pcb
	(version 20260206)
	(generator "pcbnew")
	(generator_version "10.0")
	(general
		(thickness 1.6)
		(legacy_teardrops no)
	)
	(paper "A4")
	(title_block
		(title "01162023_DA0F0TEBIF0_F0T_Expander_BD_F_brd_V02_OCP.brd")
		(comment 1 "Grand Teton / footprints 6646-6651 of 9728")
	)
	(layers
		(0 "F.Cu" signal "TOP")
		(4 "In1.Cu" signal "GND")
		(6 "In2.Cu" signal "VCC")
		(8 "In3.Cu" signal "VCC1")
		(10 "In4.Cu" signal "GND1")
		(12 "In5.Cu" signal "IN1")
		(14 "In6.Cu" signal "GND2")
		(16 "In7.Cu" signal "IN2")
		(18 "In8.Cu" signal "GND3")
		(20 "In9.Cu" signal "IN3")
		(22 "In10.Cu" signal "GND4")
		(24 "In11.Cu" signal "IN4")
		(26 "In12.Cu" signal "GND5")
		(28 "In13.Cu" signal "IN5")
		(30 "In14.Cu" signal "GND6")
		(32 "In15.Cu" signal "IN6")
		(34 "In16.Cu" signal "GND7")
		(2 "B.Cu" signal "BOTTOM")
		(9 "F.Adhes" user "F.Adhesive")
		(11 "B.Adhes" user "B.Adhesive")
		(13 "F.Paste" user "Package Geometry/Pastemask Top")
		(15 "B.Paste" user "Package Geometry/Pastemask Bottom")
		(5 "F.SilkS" user "Ref Des/Silkscreen Top")
		(7 "B.SilkS" user "Ref Des/Silkscreen Bottom")
		(1 "F.Mask" user "Board Geometry/Soldermask Top")
		(3 "B.Mask" user "Board Geometry/Soldermask Bottom")
		(17 "Dwgs.User" user "User.Drawings")
		(19 "Cmts.User" user "User.Comments")
		(21 "Eco1.User" user "User.Eco1")
		(23 "Eco2.User" user "User.Eco2")
		(25 "Edge.Cuts" user "Board Geometry/Outline")
		(27 "Margin" user)
		(31 "F.CrtYd" user "Package Geometry/Place Bound Top")
		(29 "B.CrtYd" user "Package Geometry/Place Bound Bottom")
		(35 "F.Fab" user "Ref Des/Assembly Top")
		(33 "B.Fab" user "Ref Des/Assembly Bottom")
	)
	(footprint ""
		(layer "F.Cu")
		(at 211.512404 -213.881716 90)
		(property "Reference" "C2571"
			(at 0 0 90)
			(layer "F.SilkS")
			(hide yes)
			(effects
				(font
					(size 1.27 1.27)
				)
			)
		)
		(property "Value" ""
			(at 0 0 90)
			(layer "F.Fab")
			(effects
				(font
					(size 1.27 1.27)
				)
			)
		)
		(duplicate_pad_numbers_are_jumpers no)
		(fp_line
			(start 0.7874 -0.4064)
			(end 0.7874 0.4064)
			(stroke
				(width 0.1524)
				(type default)
			)
			(layer "F.SilkS")
		)
		(fp_line
			(start -0.7874 -0.4064)
			(end 0.7874 -0.4064)
			(stroke
				(width 0.1524)
				(type default)
			)
			(layer "F.SilkS")
		)
		(fp_line
			(start 0.7874 0.4064)
			(end -0.7874 0.4064)
			(stroke
				(width 0.1524)
				(type default)
			)
			(layer "F.SilkS")
		)
		(fp_line
			(start -0.7874 0.4064)
			(end -0.7874 -0.4064)
			(stroke
				(width 0.1524)
				(type default)
			)
			(layer "F.SilkS")
		)
		(fp_line
			(start -0.12065 -0.305054)
			(end -0.12065 -0.2794)
			(stroke
				(width 0.1)
				(type default)
			)
			(layer "F.Fab")
		)
		(fp_line
			(start -0.67945 -0.305054)
			(end -0.12065 -0.305054)
			(stroke
				(width 0.1)
				(type default)
			)
			(layer "F.Fab")
		)
		(fp_line
			(start 0.67945 -0.3048)
			(end 0.67945 0.3048)
			(stroke
				(width 0.1)
				(type default)
			)
			(layer "F.Fab")
		)
		(fp_line
			(start 0.12065 -0.3048)
			(end 0.67945 -0.3048)
			(stroke
				(width 0.1)
				(type default)
			)
			(layer "F.Fab")
		)
		(fp_line
			(start 0.12065 -0.2794)
			(end 0.12065 -0.3048)
			(stroke
				(width 0.1)
				(type default)
			)
			(layer "F.Fab")
		)
		(fp_line
			(start -0.12065 -0.2794)
			(end 0.12065 -0.2794)
			(stroke
				(width 0.1)
				(type default)
			)
			(layer "F.Fab")
		)
		(fp_line
			(start 0.120396 0.2794)
			(end -0.12065 0.2794)
			(stroke
				(width 0.1)
				(type default)
			)
			(layer "F.Fab")
		)
		(fp_line
			(start -0.12065 0.2794)
			(end -0.12065 0.3048)
			(stroke
				(width 0.1)
				(type default)
			)
			(layer "F.Fab")
		)
		(fp_line
			(start 0.67945 0.3048)
			(end 0.120396 0.3048)
			(stroke
				(width 0.1)
				(type default)
			)
			(layer "F.Fab")
		)
		(fp_line
			(start 0.120396 0.3048)
			(end 0.120396 0.2794)
			(stroke
				(width 0.1)
				(type default)
			)
			(layer "F.Fab")
		)
		(fp_line
			(start -0.12065 0.3048)
			(end -0.67945 0.3048)
			(stroke
				(width 0.1)
				(type default)
			)
			(layer "F.Fab")
		)
		(fp_line
			(start -0.67945 0.3048)
			(end -0.67945 -0.305054)
			(stroke
				(width 0.1)
				(type default)
			)
			(layer "F.Fab")
		)
		(pad "1" smd circle
			(at -0.40005 0 90)
			(size 0 0)
			(layers "F.Cu" "F.Mask" "F.Paste")
			(net "GND")
		)
		(pad "2" smd circle
			(at 0.40005 0 90)
			(size 0 0)
			(layers "F.Cu" "F.Mask" "F.Paste")
			(net "P3V3_AUX")
		)
	)
	(footprint ""
		(layer "F.Cu")
		(at 104.243632 -45.88891)
		(property "Reference" "R543"
			(at 0 0 0)
			(layer "F.SilkS")
			(hide yes)
			(effects
				(font
					(size 1.27 1.27)
				)
			)
		)
		(property "Value" ""
			(at 0 0 0)
			(layer "F.Fab")
			(effects
				(font
					(size 1.27 1.27)
				)
			)
		)
		(duplicate_pad_numbers_are_jumpers no)
		(fp_line
			(start -0.7874 -0.4064)
			(end 0.7874 -0.4064)
			(stroke
				(width 0.1524)
				(type default)
			)
			(layer "F.SilkS")
		)
		(fp_line
			(start -0.7874 0.4064)
			(end -0.7874 -0.4064)
			(stroke
				(width 0.1524)
				(type default)
			)
			(layer "F.SilkS")
		)
		(fp_line
			(start 0.7874 -0.4064)
			(end 0.7874 0.4064)
			(stroke
				(width 0.1524)
				(type default)
			)
			(layer "F.SilkS")
		)
		(fp_line
			(start 0.7874 0.4064)
			(end -0.7874 0.4064)
			(stroke
				(width 0.1524)
				(type default)
			)
			(layer "F.SilkS")
		)
		(fp_line
			(start -0.67945 -0.305054)
			(end -0.12065 -0.305054)
			(stroke
				(width 0.1)
				(type default)
			)
			(layer "F.Fab")
		)
		(fp_line
			(start -0.67945 0.3048)
			(end -0.67945 -0.305054)
			(stroke
				(width 0.1)
				(type default)
			)
			(layer "F.Fab")
		)
		(fp_line
			(start -0.12065 -0.305054)
			(end -0.12065 -0.2794)
			(stroke
				(width 0.1)
				(type default)
			)
			(layer "F.Fab")
		)
		(fp_line
			(start -0.12065 -0.2794)
			(end 0.12065 -0.2794)
			(stroke
				(width 0.1)
				(type default)
			)
			(layer "F.Fab")
		)
		(fp_line
			(start -0.12065 0.2794)
			(end -0.12065 0.3048)
			(stroke
				(width 0.1)
				(type default)
			)
			(layer "F.Fab")
		)
		(fp_line
			(start -0.12065 0.3048)
			(end -0.67945 0.3048)
			(stroke
				(width 0.1)
				(type default)
			)
			(layer "F.Fab")
		)
		(fp_line
			(start 0.120396 0.2794)
			(end -0.12065 0.2794)
			(stroke
				(width 0.1)
				(type default)
			)
			(layer "F.Fab")
		)
		(fp_line
			(start 0.120396 0.3048)
			(end 0.120396 0.2794)
			(stroke
				(width 0.1)
				(type default)
			)
			(layer "F.Fab")
		)
		(fp_line
			(start 0.12065 -0.3048)
			(end 0.67945 -0.3048)
			(stroke
				(width 0.1)
				(type default)
			)
			(layer "F.Fab")
		)
		(fp_line
			(start 0.12065 -0.2794)
			(end 0.12065 -0.3048)
			(stroke
				(width 0.1)
				(type default)
			)
			(layer "F.Fab")
		)
		(fp_line
			(start 0.67945 -0.3048)
			(end 0.67945 0.3048)
			(stroke
				(width 0.1)
				(type default)
			)
			(layer "F.Fab")
		)
		(fp_line
			(start 0.67945 0.3048)
			(end 0.120396 0.3048)
			(stroke
				(width 0.1)
				(type default)
			)
			(layer "F.Fab")
		)
		(pad "1" smd circle
			(at -0.40005 0)
			(size 0 0)
			(layers "F.Cu" "F.Mask" "F.Paste")
			(net "SSD3_ADC_A0")
		)
		(pad "2" smd circle
			(at 0.40005 0)
			(size 0 0)
			(layers "F.Cu" "F.Mask" "F.Paste")
			(net "GND")
		)
	)
	(footprint ""
		(layer "F.Cu")
		(at 102.027736 -275.813774 180)
		(property "Reference" "PC6610"
			(at 0 0 180)
			(layer "F.SilkS")
			(hide yes)
			(effects
				(font
					(size 1.27 1.27)
				)
			)
		)
		(property "Value" ""
			(at 0 0 180)
			(layer "F.Fab")
			(effects
				(font
					(size 1.27 1.27)
				)
			)
		)
		(duplicate_pad_numbers_are_jumpers no)
		(fp_line
			(start 1.524 0.762)
			(end -1.524 0.762)
			(stroke
				(width 0.1524)
				(type default)
			)
			(layer "F.SilkS")
		)
		(fp_line
			(start 1.524 -0.762)
			(end 1.524 0.762)
			(stroke
				(width 0.1524)
				(type default)
			)
			(layer "F.SilkS")
		)
		(fp_line
			(start -1.524 0.762)
			(end -1.524 -0.762)
			(stroke
				(width 0.1524)
				(type default)
			)
			(layer "F.SilkS")
		)
		(fp_line
			(start -1.524 -0.762)
			(end 1.524 -0.762)
			(stroke
				(width 0.1524)
				(type default)
			)
			(layer "F.SilkS")
		)
		(fp_line
			(start 1.1049 0.724916)
			(end 1.1049 -0.724916)
			(stroke
				(width 0.1)
				(type default)
			)
			(layer "F.Fab")
		)
		(fp_line
			(start 1.1049 -0.724916)
			(end -1.1049 -0.724916)
			(stroke
				(width 0.1)
				(type default)
			)
			(layer "F.Fab")
		)
		(fp_line
			(start -1.1049 0.724916)
			(end 1.1049 0.724916)
			(stroke
				(width 0.1)
				(type default)
			)
			(layer "F.Fab")
		)
		(fp_line
			(start -1.1049 -0.724916)
			(end -1.1049 0.724916)
			(stroke
				(width 0.1)
				(type default)
			)
			(layer "F.Fab")
		)
		(pad "1" smd rect
			(at -0.889 0)
			(size 1.016 1.27)
			(layers "F.Cu" "F.Mask" "F.Paste")
			(net "SW_P12V_P0V8_PEX0_FLT")
		)
		(pad "2" smd rect
			(at 0.889 0)
			(size 1.016 1.27)
			(layers "F.Cu" "F.Mask" "F.Paste")
			(net "GND")
		)
	)
	(footprint ""
		(layer "F.Cu")
		(at 429.175164 -63.086234)
		(property "Reference" "R6029"
			(at 0 0 0)
			(layer "F.SilkS")
			(hide yes)
			(effects
				(font
					(size 1.27 1.27)
				)
			)
		)
		(property "Value" ""
			(at 0 0 0)
			(layer "F.Fab")
			(effects
				(font
					(size 1.27 1.27)
				)
			)
		)
		(duplicate_pad_numbers_are_jumpers no)
		(fp_line
			(start -0.7874 -0.4064)
			(end 0.7874 -0.4064)
			(stroke
				(width 0.1524)
				(type default)
			)
			(layer "F.SilkS")
		)
		(fp_line
			(start -0.7874 0.4064)
			(end -0.7874 -0.4064)
			(stroke
				(width 0.1524)
				(type default)
			)
			(layer "F.SilkS")
		)
		(fp_line
			(start 0.7874 -0.4064)
			(end 0.7874 0.4064)
			(stroke
				(width 0.1524)
				(type default)
			)
			(layer "F.SilkS")
		)
		(fp_line
			(start 0.7874 0.4064)
			(end -0.7874 0.4064)
			(stroke
				(width 0.1524)
				(type default)
			)
			(layer "F.SilkS")
		)
		(fp_line
			(start -0.67945 -0.305054)
			(end -0.12065 -0.305054)
			(stroke
				(width 0.1)
				(type default)
			)
			(layer "F.Fab")
		)
		(fp_line
			(start -0.67945 0.3048)
			(end -0.67945 -0.305054)
			(stroke
				(width 0.1)
				(type default)
			)
			(layer "F.Fab")
		)
		(fp_line
			(start -0.12065 -0.305054)
			(end -0.12065 -0.2794)
			(stroke
				(width 0.1)
				(type default)
			)
			(layer "F.Fab")
		)
		(fp_line
			(start -0.12065 -0.2794)
			(end 0.12065 -0.2794)
			(stroke
				(width 0.1)
				(type default)
			)
			(layer "F.Fab")
		)
		(fp_line
			(start -0.12065 0.2794)
			(end -0.12065 0.3048)
			(stroke
				(width 0.1)
				(type default)
			)
			(layer "F.Fab")
		)
		(fp_line
			(start -0.12065 0.3048)
			(end -0.67945 0.3048)
			(stroke
				(width 0.1)
				(type default)
			)
			(layer "F.Fab")
		)
		(fp_line
			(start 0.120396 0.2794)
			(end -0.12065 0.2794)
			(stroke
				(width 0.1)
				(type default)
			)
			(layer "F.Fab")
		)
		(fp_line
			(start 0.120396 0.3048)
			(end 0.120396 0.2794)
			(stroke
				(width 0.1)
				(type default)
			)
			(layer "F.Fab")
		)
		(fp_line
			(start 0.12065 -0.3048)
			(end 0.67945 -0.3048)
			(stroke
				(width 0.1)
				(type default)
			)
			(layer "F.Fab")
		)
		(fp_line
			(start 0.12065 -0.2794)
			(end 0.12065 -0.3048)
			(stroke
				(width 0.1)
				(type default)
			)
			(layer "F.Fab")
		)
		(fp_line
			(start 0.67945 -0.3048)
			(end 0.67945 0.3048)
			(stroke
				(width 0.1)
				(type default)
			)
			(layer "F.Fab")
		)
		(fp_line
			(start 0.67945 0.3048)
			(end 0.120396 0.3048)
			(stroke
				(width 0.1)
				(type default)
			)
			(layer "F.Fab")
		)
		(pad "1" smd circle
			(at -0.40005 0)
			(size 0 0)
			(layers "F.Cu" "F.Mask" "F.Paste")
			(net "P12V_SSD15_R")
		)
		(pad "2" smd circle
			(at 0.40005 0)
			(size 0 0)
			(layers "F.Cu" "F.Mask" "F.Paste")
			(net "P12V_SSD15_PG_G1")
		)
	)
	(footprint ""
		(layer "F.Cu")
		(at 212.451442 -244.016276 90)
		(property "Reference" "R1537"
			(at 0 0 90)
			(layer "F.SilkS")
			(hide yes)
			(effects
				(font
					(size 1.27 1.27)
				)
			)
		)
		(property "Value" ""
			(at 0 0 90)
			(layer "F.Fab")
			(effects
				(font
					(size 1.27 1.27)
				)
			)
		)
		(duplicate_pad_numbers_are_jumpers no)
		(fp_line
			(start 0.7874 -0.4064)
			(end 0.7874 0.4064)
			(stroke
				(width 0.1524)
				(type default)
			)
			(layer "F.SilkS")
		)
		(fp_line
			(start -0.7874 -0.4064)
			(end 0.7874 -0.4064)
			(stroke
				(width 0.1524)
				(type default)
			)
			(layer "F.SilkS")
		)
		(fp_line
			(start 0.7874 0.4064)
			(end -0.7874 0.4064)
			(stroke
				(width 0.1524)
				(type default)
			)
			(layer "F.SilkS")
		)
		(fp_line
			(start -0.7874 0.4064)
			(end -0.7874 -0.4064)
			(stroke
				(width 0.1524)
				(type default)
			)
			(layer "F.SilkS")
		)
		(fp_line
			(start -0.12065 -0.305054)
			(end -0.12065 -0.2794)
			(stroke
				(width 0.1)
				(type default)
			)
			(layer "F.Fab")
		)
		(fp_line
			(start -0.67945 -0.305054)
			(end -0.12065 -0.305054)
			(stroke
				(width 0.1)
				(type default)
			)
			(layer "F.Fab")
		)
		(fp_line
			(start 0.67945 -0.3048)
			(end 0.67945 0.3048)
			(stroke
				(width 0.1)
				(type default)
			)
			(layer "F.Fab")
		)
		(fp_line
			(start 0.12065 -0.3048)
			(end 0.67945 -0.3048)
			(stroke
				(width 0.1)
				(type default)
			)
			(layer "F.Fab")
		)
		(fp_line
			(start 0.12065 -0.2794)
			(end 0.12065 -0.3048)
			(stroke
				(width 0.1)
				(type default)
			)
			(layer "F.Fab")
		)
		(fp_line
			(start -0.12065 -0.2794)
			(end 0.12065 -0.2794)
			(stroke
				(width 0.1)
				(type default)
			)
			(layer "F.Fab")
		)
		(fp_line
			(start 0.120396 0.2794)
			(end -0.12065 0.2794)
			(stroke
				(width 0.1)
				(type default)
			)
			(layer "F.Fab")
		)
		(fp_line
			(start -0.12065 0.2794)
			(end -0.12065 0.3048)
			(stroke
				(width 0.1)
				(type default)
			)
			(layer "F.Fab")
		)
		(fp_line
			(start 0.67945 0.3048)
			(end 0.120396 0.3048)
			(stroke
				(width 0.1)
				(type default)
			)
			(layer "F.Fab")
		)
		(fp_line
			(start 0.120396 0.3048)
			(end 0.120396 0.2794)
			(stroke
				(width 0.1)
				(type default)
			)
			(layer "F.Fab")
		)
		(fp_line
			(start -0.12065 0.3048)
			(end -0.67945 0.3048)
			(stroke
				(width 0.1)
				(type default)
			)
			(layer "F.Fab")
		)
		(fp_line
			(start -0.67945 0.3048)
			(end -0.67945 -0.305054)
			(stroke
				(width 0.1)
				(type default)
			)
			(layer "F.Fab")
		)
		(pad "1" smd circle
			(at -0.40005 0 90)
			(size 0 0)
			(layers "F.Cu" "F.Mask" "F.Paste")
			(net "SMB_PEX_R_SDA")
		)
		(pad "2" smd circle
			(at 0.40005 0 90)
			(size 0 0)
			(layers "F.Cu" "F.Mask" "F.Paste")
			(net "P3V3_AUX")
		)
	)
	(footprint ""
		(layer "F.Cu")
		(at 121.108978 -88.39073)
		(property "Reference" "R1561"
			(at 0 0 0)
			(layer "F.SilkS")
			(hide yes)
			(effects
				(font
					(size 1.27 1.27)
				)
			)
		)
		(property "Value" ""
			(at 0 0 0)
			(layer "F.Fab")
			(effects
				(font
					(size 1.27 1.27)
				)
			)
		)
		(duplicate_pad_numbers_are_jumpers no)
		(fp_line
			(start -0.7874 -0.4064)
			(end 0.7874 -0.4064)
			(stroke
				(width 0.1524)
				(type default)
			)
			(layer "F.SilkS")
		)
		(fp_line
			(start -0.7874 0.4064)
			(end -0.7874 -0.4064)
			(stroke
				(width 0.1524)
				(type default)
			)
			(layer "F.SilkS")
		)
		(fp_line
			(start 0.7874 -0.4064)
			(end 0.7874 0.4064)
			(stroke
				(width 0.1524)
				(type default)
			)
			(layer "F.SilkS")
		)
		(fp_line
			(start 0.7874 0.4064)
			(end -0.7874 0.4064)
			(stroke
				(width 0.1524)
				(type default)
			)
			(layer "F.SilkS")
		)
		(fp_line
			(start -0.67945 -0.305054)
			(end -0.12065 -0.305054)
			(stroke
				(width 0.1)
				(type default)
			)
			(layer "F.Fab")
		)
		(fp_line
			(start -0.67945 0.3048)
			(end -0.67945 -0.305054)
			(stroke
				(width 0.1)
				(type default)
			)
			(layer "F.Fab")
		)
		(fp_line
			(start -0.12065 -0.305054)
			(end -0.12065 -0.2794)
			(stroke
				(width 0.1)
				(type default)
			)
			(layer "F.Fab")
		)
		(fp_line
			(start -0.12065 -0.2794)
			(end 0.12065 -0.2794)
			(stroke
				(width 0.1)
				(type default)
			)
			(layer "F.Fab")
		)
		(fp_line
			(start -0.12065 0.2794)
			(end -0.12065 0.3048)
			(stroke
				(width 0.1)
				(type default)
			)
			(layer "F.Fab")
		)
		(fp_line
			(start -0.12065 0.3048)
			(end -0.67945 0.3048)
			(stroke
				(width 0.1)
				(type default)
			)
			(layer "F.Fab")
		)
		(fp_line
			(start 0.120396 0.2794)
			(end -0.12065 0.2794)
			(stroke
				(width 0.1)
				(type default)
			)
			(layer "F.Fab")
		)
		(fp_line
			(start 0.120396 0.3048)
			(end 0.120396 0.2794)
			(stroke
				(width 0.1)
				(type default)
			)
			(layer "F.Fab")
		)
		(fp_line
			(start 0.12065 -0.3048)
			(end 0.67945 -0.3048)
			(stroke
				(width 0.1)
				(type default)
			)
			(layer "F.Fab")
		)
		(fp_line
			(start 0.12065 -0.2794)
			(end 0.12065 -0.3048)
			(stroke
				(width 0.1)
				(type default)
			)
			(layer "F.Fab")
		)
		(fp_line
			(start 0.67945 -0.3048)
			(end 0.67945 0.3048)
			(stroke
				(width 0.1)
				(type default)
			)
			(layer "F.Fab")
		)
		(fp_line
			(start 0.67945 0.3048)
			(end 0.120396 0.3048)
			(stroke
				(width 0.1)
				(type default)
			)
			(layer "F.Fab")
		)
		(pad "1" smd circle
			(at -0.40005 0)
			(size 0 0)
			(layers "F.Cu" "F.Mask" "F.Paste")
			(net "P3V3_AUX")
		)
		(pad "2" smd circle
			(at 0.40005 0)
			(size 0 0)
			(layers "F.Cu" "F.Mask" "F.Paste")
			(net "SMB_BIC_I2C9_MUX0_SSD3_R_SCL")
		)
	)
)
